(kicad_pcb
	(version 20260206)
	(generator "pcbnew")
	(generator_version "10.0")
	(general
		(thickness 1.6)
		(legacy_teardrops no)
	)
	(paper "A4")
	(title_block
		(title "03242023_DA0F0TMBIJ0_F0T_Motherboard_J_brd_V01_OCP.brd")
		(comment 1 "Grand Teton / footprints 2973-2979 of 6105")
	)
	(layers
		(0 "F.Cu" signal "TOP")
		(4 "In1.Cu" signal "GND")
		(6 "In2.Cu" signal "IN1")
		(8 "In3.Cu" signal "GND1")
		(10 "In4.Cu" signal "IN2")
		(12 "In5.Cu" signal "GND2")
		(14 "In6.Cu" signal "IN3")
		(16 "In7.Cu" signal "GND3")
		(18 "In8.Cu" signal "VCC")
		(20 "In9.Cu" signal "VCC1")
		(22 "In10.Cu" signal "GND4")
		(24 "In11.Cu" signal "IN4")
		(26 "In12.Cu" signal "GND5")
		(28 "In13.Cu" signal "IN5")
		(30 "In14.Cu" signal "GND6")
		(32 "In15.Cu" signal "IN6")
		(34 "In16.Cu" signal "GND7")
		(2 "B.Cu" signal "BOTTOM")
		(9 "F.Adhes" user "F.Adhesive")
		(11 "B.Adhes" user "B.Adhesive")
		(13 "F.Paste" user "Package Geometry/Pastemask Top")
		(15 "B.Paste" user "Package Geometry/Pastemask Bottom")
		(5 "F.SilkS" user "Ref Des/Silkscreen Top")
		(7 "B.SilkS" user "Ref Des/Silkscreen Bottom")
		(1 "F.Mask" user "Board Geometry/Soldermask Top")
		(3 "B.Mask" user "Board Geometry/Soldermask Bottom")
		(17 "Dwgs.User" user "User.Drawings")
		(19 "Cmts.User" user "User.Comments")
		(21 "Eco1.User" user "User.Eco1")
		(23 "Eco2.User" user "User.Eco2")
		(25 "Edge.Cuts" user "Board Geometry/Outline")
		(27 "Margin" user)
		(31 "F.CrtYd" user "Package Geometry/Place Bound Top")
		(29 "B.CrtYd" user "Package Geometry/Place Bound Bottom")
		(35 "F.Fab" user "Ref Des/Assembly Top")
		(33 "B.Fab" user "Ref Des/Assembly Bottom")
	)
	(footprint ""
		(layer "F.Cu")
		(at 309.522622 -40.122348 180)
		(property "Reference" "R1451"
			(at 0 0 180)
			(layer "F.SilkS")
			(hide yes)
			(effects
				(font
					(size 1.27 1.27)
				)
			)
		)
		(property "Value" ""
			(at 0 0 180)
			(layer "F.Fab")
			(effects
				(font
					(size 1.27 1.27)
				)
			)
		)
		(duplicate_pad_numbers_are_jumpers no)
		(fp_line
			(start 0.7874 0.4064)
			(end -0.7874 0.4064)
			(stroke
				(width 0.1524)
				(type default)
			)
			(layer "F.SilkS")
		)
		(fp_line
			(start 0.7874 -0.4064)
			(end 0.7874 0.4064)
			(stroke
				(width 0.1524)
				(type default)
			)
			(layer "F.SilkS")
		)
		(fp_line
			(start -0.7874 0.4064)
			(end -0.7874 -0.4064)
			(stroke
				(width 0.1524)
				(type default)
			)
			(layer "F.SilkS")
		)
		(fp_line
			(start -0.7874 -0.4064)
			(end 0.7874 -0.4064)
			(stroke
				(width 0.1524)
				(type default)
			)
			(layer "F.SilkS")
		)
		(fp_line
			(start 0.67945 0.3048)
			(end 0.120396 0.3048)
			(stroke
				(width 0.1)
				(type default)
			)
			(layer "F.Fab")
		)
		(fp_line
			(start 0.67945 -0.3048)
			(end 0.67945 0.3048)
			(stroke
				(width 0.1)
				(type default)
			)
			(layer "F.Fab")
		)
		(fp_line
			(start 0.12065 -0.2794)
			(end 0.12065 -0.3048)
			(stroke
				(width 0.1)
				(type default)
			)
			(layer "F.Fab")
		)
		(fp_line
			(start 0.12065 -0.3048)
			(end 0.67945 -0.3048)
			(stroke
				(width 0.1)
				(type default)
			)
			(layer "F.Fab")
		)
		(fp_line
			(start 0.120396 0.3048)
			(end 0.120396 0.2794)
			(stroke
				(width 0.1)
				(type default)
			)
			(layer "F.Fab")
		)
		(fp_line
			(start 0.120396 0.2794)
			(end -0.12065 0.2794)
			(stroke
				(width 0.1)
				(type default)
			)
			(layer "F.Fab")
		)
		(fp_line
			(start -0.12065 0.3048)
			(end -0.67945 0.3048)
			(stroke
				(width 0.1)
				(type default)
			)
			(layer "F.Fab")
		)
		(fp_line
			(start -0.12065 0.2794)
			(end -0.12065 0.3048)
			(stroke
				(width 0.1)
				(type default)
			)
			(layer "F.Fab")
		)
		(fp_line
			(start -0.12065 -0.2794)
			(end 0.12065 -0.2794)
			(stroke
				(width 0.1)
				(type default)
			)
			(layer "F.Fab")
		)
		(fp_line
			(start -0.12065 -0.305054)
			(end -0.12065 -0.2794)
			(stroke
				(width 0.1)
				(type default)
			)
			(layer "F.Fab")
		)
		(fp_line
			(start -0.67945 0.3048)
			(end -0.67945 -0.305054)
			(stroke
				(width 0.1)
				(type default)
			)
			(layer "F.Fab")
		)
		(fp_line
			(start -0.67945 -0.305054)
			(end -0.12065 -0.305054)
			(stroke
				(width 0.1)
				(type default)
			)
			(layer "F.Fab")
		)
		(pad "1" smd circle
			(at -0.40005 0 180)
			(size 0 0)
			(layers "F.Cu" "F.Mask" "F.Paste")
			(net "PU_SMB_SML3_3V3AUX_PCH_SCL")
		)
		(pad "2" smd circle
			(at 0.40005 0 180)
			(size 0 0)
			(layers "F.Cu" "F.Mask" "F.Paste")
			(net "P3V3_AUX")
		)
	)
	(footprint ""
		(layer "F.Cu")
		(at 298.16552 -408.7114)
		(property "Reference" "R4895"
			(at 0 0 0)
			(layer "F.SilkS")
			(hide yes)
			(effects
				(font
					(size 1.27 1.27)
				)
			)
		)
		(property "Value" ""
			(at 0 0 0)
			(layer "F.Fab")
			(effects
				(font
					(size 1.27 1.27)
				)
			)
		)
		(duplicate_pad_numbers_are_jumpers no)
		(fp_line
			(start -0.7874 -0.4064)
			(end 0.7874 -0.4064)
			(stroke
				(width 0.1524)
				(type default)
			)
			(layer "F.SilkS")
		)
		(fp_line
			(start -0.7874 0.4064)
			(end -0.7874 -0.4064)
			(stroke
				(width 0.1524)
				(type default)
			)
			(layer "F.SilkS")
		)
		(fp_line
			(start 0.7874 -0.4064)
			(end 0.7874 0.4064)
			(stroke
				(width 0.1524)
				(type default)
			)
			(layer "F.SilkS")
		)
		(fp_line
			(start 0.7874 0.4064)
			(end -0.7874 0.4064)
			(stroke
				(width 0.1524)
				(type default)
			)
			(layer "F.SilkS")
		)
		(fp_line
			(start -0.67945 -0.305054)
			(end -0.12065 -0.305054)
			(stroke
				(width 0.1)
				(type default)
			)
			(layer "F.Fab")
		)
		(fp_line
			(start -0.67945 0.3048)
			(end -0.67945 -0.305054)
			(stroke
				(width 0.1)
				(type default)
			)
			(layer "F.Fab")
		)
		(fp_line
			(start -0.12065 -0.305054)
			(end -0.12065 -0.2794)
			(stroke
				(width 0.1)
				(type default)
			)
			(layer "F.Fab")
		)
		(fp_line
			(start -0.12065 -0.2794)
			(end 0.12065 -0.2794)
			(stroke
				(width 0.1)
				(type default)
			)
			(layer "F.Fab")
		)
		(fp_line
			(start -0.12065 0.2794)
			(end -0.12065 0.3048)
			(stroke
				(width 0.1)
				(type default)
			)
			(layer "F.Fab")
		)
		(fp_line
			(start -0.12065 0.3048)
			(end -0.67945 0.3048)
			(stroke
				(width 0.1)
				(type default)
			)
			(layer "F.Fab")
		)
		(fp_line
			(start 0.120396 0.2794)
			(end -0.12065 0.2794)
			(stroke
				(width 0.1)
				(type default)
			)
			(layer "F.Fab")
		)
		(fp_line
			(start 0.120396 0.3048)
			(end 0.120396 0.2794)
			(stroke
				(width 0.1)
				(type default)
			)
			(layer "F.Fab")
		)
		(fp_line
			(start 0.12065 -0.3048)
			(end 0.67945 -0.3048)
			(stroke
				(width 0.1)
				(type default)
			)
			(layer "F.Fab")
		)
		(fp_line
			(start 0.12065 -0.2794)
			(end 0.12065 -0.3048)
			(stroke
				(width 0.1)
				(type default)
			)
			(layer "F.Fab")
		)
		(fp_line
			(start 0.67945 -0.3048)
			(end 0.67945 0.3048)
			(stroke
				(width 0.1)
				(type default)
			)
			(layer "F.Fab")
		)
		(fp_line
			(start 0.67945 0.3048)
			(end 0.120396 0.3048)
			(stroke
				(width 0.1)
				(type default)
			)
			(layer "F.Fab")
		)
		(pad "1" smd circle
			(at -0.40005 0)
			(size 0 0)
			(layers "F.Cu" "F.Mask" "F.Paste")
			(net "P12V_HSC_TEMP_SDA")
		)
		(pad "2" smd circle
			(at 0.40005 0)
			(size 0 0)
			(layers "F.Cu" "F.Mask" "F.Paste")
			(net "SMB_LM75_0_3V3AUX_SDA")
		)
	)
	(footprint ""
		(layer "F.Cu")
		(at 36.930584 -112.619282)
		(property "Reference" "C2046"
			(at 0 0 0)
			(layer "F.SilkS")
			(hide yes)
			(effects
				(font
					(size 1.27 1.27)
				)
			)
		)
		(property "Value" ""
			(at 0 0 0)
			(layer "F.Fab")
			(effects
				(font
					(size 1.27 1.27)
				)
			)
		)
		(duplicate_pad_numbers_are_jumpers no)
		(fp_line
			(start -0.7874 -0.4064)
			(end 0.7874 -0.4064)
			(stroke
				(width 0.1524)
				(type default)
			)
			(layer "F.SilkS")
		)
		(fp_line
			(start -0.7874 0.4064)
			(end -0.7874 -0.4064)
			(stroke
				(width 0.1524)
				(type default)
			)
			(layer "F.SilkS")
		)
		(fp_line
			(start 0.7874 -0.4064)
			(end 0.7874 0.4064)
			(stroke
				(width 0.1524)
				(type default)
			)
			(layer "F.SilkS")
		)
		(fp_line
			(start 0.7874 0.4064)
			(end -0.7874 0.4064)
			(stroke
				(width 0.1524)
				(type default)
			)
			(layer "F.SilkS")
		)
		(fp_line
			(start -0.67945 -0.305054)
			(end -0.12065 -0.305054)
			(stroke
				(width 0.1)
				(type default)
			)
			(layer "F.Fab")
		)
		(fp_line
			(start -0.67945 0.3048)
			(end -0.67945 -0.305054)
			(stroke
				(width 0.1)
				(type default)
			)
			(layer "F.Fab")
		)
		(fp_line
			(start -0.12065 -0.305054)
			(end -0.12065 -0.2794)
			(stroke
				(width 0.1)
				(type default)
			)
			(layer "F.Fab")
		)
		(fp_line
			(start -0.12065 -0.2794)
			(end 0.12065 -0.2794)
			(stroke
				(width 0.1)
				(type default)
			)
			(layer "F.Fab")
		)
		(fp_line
			(start -0.12065 0.2794)
			(end -0.12065 0.3048)
			(stroke
				(width 0.1)
				(type default)
			)
			(layer "F.Fab")
		)
		(fp_line
			(start -0.12065 0.3048)
			(end -0.67945 0.3048)
			(stroke
				(width 0.1)
				(type default)
			)
			(layer "F.Fab")
		)
		(fp_line
			(start 0.120396 0.2794)
			(end -0.12065 0.2794)
			(stroke
				(width 0.1)
				(type default)
			)
			(layer "F.Fab")
		)
		(fp_line
			(start 0.120396 0.3048)
			(end 0.120396 0.2794)
			(stroke
				(width 0.1)
				(type default)
			)
			(layer "F.Fab")
		)
		(fp_line
			(start 0.12065 -0.3048)
			(end 0.67945 -0.3048)
			(stroke
				(width 0.1)
				(type default)
			)
			(layer "F.Fab")
		)
		(fp_line
			(start 0.12065 -0.2794)
			(end 0.12065 -0.3048)
			(stroke
				(width 0.1)
				(type default)
			)
			(layer "F.Fab")
		)
		(fp_line
			(start 0.67945 -0.3048)
			(end 0.67945 0.3048)
			(stroke
				(width 0.1)
				(type default)
			)
			(layer "F.Fab")
		)
		(fp_line
			(start 0.67945 0.3048)
			(end 0.120396 0.3048)
			(stroke
				(width 0.1)
				(type default)
			)
			(layer "F.Fab")
		)
		(pad "1" smd circle
			(at -0.40005 0)
			(size 0 0)
			(layers "F.Cu" "F.Mask" "F.Paste")
			(net "P12V_AUX_ADC_TIC")
		)
		(pad "2" smd circle
			(at 0.40005 0)
			(size 0 0)
			(layers "F.Cu" "F.Mask" "F.Paste")
			(net "GND")
		)
	)
	(footprint ""
		(layer "F.Cu")
		(at 197.19036 -116.804948 180)
		(property "Reference" "R1811"
			(at 0 0 180)
			(layer "F.SilkS")
			(hide yes)
			(effects
				(font
					(size 1.27 1.27)
				)
			)
		)
		(property "Value" ""
			(at 0 0 180)
			(layer "F.Fab")
			(effects
				(font
					(size 1.27 1.27)
				)
			)
		)
		(duplicate_pad_numbers_are_jumpers no)
		(fp_line
			(start 0.7874 0.4064)
			(end -0.7874 0.4064)
			(stroke
				(width 0.1524)
				(type default)
			)
			(layer "F.SilkS")
		)
		(fp_line
			(start 0.7874 -0.4064)
			(end 0.7874 0.4064)
			(stroke
				(width 0.1524)
				(type default)
			)
			(layer "F.SilkS")
		)
		(fp_line
			(start -0.7874 0.4064)
			(end -0.7874 -0.4064)
			(stroke
				(width 0.1524)
				(type default)
			)
			(layer "F.SilkS")
		)
		(fp_line
			(start -0.7874 -0.4064)
			(end 0.7874 -0.4064)
			(stroke
				(width 0.1524)
				(type default)
			)
			(layer "F.SilkS")
		)
		(fp_line
			(start 0.67945 0.3048)
			(end 0.120396 0.3048)
			(stroke
				(width 0.1)
				(type default)
			)
			(layer "F.Fab")
		)
		(fp_line
			(start 0.67945 -0.3048)
			(end 0.67945 0.3048)
			(stroke
				(width 0.1)
				(type default)
			)
			(layer "F.Fab")
		)
		(fp_line
			(start 0.12065 -0.2794)
			(end 0.12065 -0.3048)
			(stroke
				(width 0.1)
				(type default)
			)
			(layer "F.Fab")
		)
		(fp_line
			(start 0.12065 -0.3048)
			(end 0.67945 -0.3048)
			(stroke
				(width 0.1)
				(type default)
			)
			(layer "F.Fab")
		)
		(fp_line
			(start 0.120396 0.3048)
			(end 0.120396 0.2794)
			(stroke
				(width 0.1)
				(type default)
			)
			(layer "F.Fab")
		)
		(fp_line
			(start 0.120396 0.2794)
			(end -0.12065 0.2794)
			(stroke
				(width 0.1)
				(type default)
			)
			(layer "F.Fab")
		)
		(fp_line
			(start -0.12065 0.3048)
			(end -0.67945 0.3048)
			(stroke
				(width 0.1)
				(type default)
			)
			(layer "F.Fab")
		)
		(fp_line
			(start -0.12065 0.2794)
			(end -0.12065 0.3048)
			(stroke
				(width 0.1)
				(type default)
			)
			(layer "F.Fab")
		)
		(fp_line
			(start -0.12065 -0.2794)
			(end 0.12065 -0.2794)
			(stroke
				(width 0.1)
				(type default)
			)
			(layer "F.Fab")
		)
		(fp_line
			(start -0.12065 -0.305054)
			(end -0.12065 -0.2794)
			(stroke
				(width 0.1)
				(type default)
			)
			(layer "F.Fab")
		)
		(fp_line
			(start -0.67945 0.3048)
			(end -0.67945 -0.305054)
			(stroke
				(width 0.1)
				(type default)
			)
			(layer "F.Fab")
		)
		(fp_line
			(start -0.67945 -0.305054)
			(end -0.12065 -0.305054)
			(stroke
				(width 0.1)
				(type default)
			)
			(layer "F.Fab")
		)
		(pad "1" smd circle
			(at -0.40005 0 180)
			(size 0 0)
			(layers "F.Cu" "F.Mask" "F.Paste")
			(net "RST_SGPIO_RESET_N")
		)
		(pad "2" smd circle
			(at 0.40005 0 180)
			(size 0 0)
			(layers "F.Cu" "F.Mask" "F.Paste")
			(net "RST_SGPIO_RESET_N_R")
		)
	)
	(footprint ""
		(layer "F.Cu")
		(at 136.360154 -402.371052 -90)
		(property "Reference" "C752"
			(at 0 0 270)
			(layer "F.SilkS")
			(hide yes)
			(effects
				(font
					(size 1.27 1.27)
				)
			)
		)
		(property "Value" ""
			(at 0 0 270)
			(layer "F.Fab")
			(effects
				(font
					(size 1.27 1.27)
				)
			)
		)
		(duplicate_pad_numbers_are_jumpers no)
		(fp_line
			(start -0.299974 0.150114)
			(end -0.299974 -0.150114)
			(stroke
				(width 0.1)
				(type default)
			)
			(layer "F.Fab")
		)
		(fp_line
			(start 0.299974 0.150114)
			(end -0.299974 0.150114)
			(stroke
				(width 0.1)
				(type default)
			)
			(layer "F.Fab")
		)
		(fp_line
			(start -0.299974 -0.150114)
			(end 0.299974 -0.150114)
			(stroke
				(width 0.1)
				(type default)
			)
			(layer "F.Fab")
		)
		(fp_line
			(start 0.299974 -0.150114)
			(end 0.299974 0.150114)
			(stroke
				(width 0.1)
				(type default)
			)
			(layer "F.Fab")
		)
		(pad "1" smd rect
			(at -0.2667 0 270)
			(size 0.3048 0.381)
			(layers "F.Cu" "F.Mask" "F.Paste")
			(net "P5E_CPU1_PE2_TX_C_DN<10>")
		)
		(pad "2" smd rect
			(at 0.2667 0 270)
			(size 0.3048 0.381)
			(layers "F.Cu" "F.Mask" "F.Paste")
			(net "P5E_CPU1_PE2_TX_DN<10>")
		)
	)
	(footprint ""
		(layer "F.Cu")
		(at 213.19744 -30.246828 90)
		(property "Reference" "R4091"
			(at 0 0 90)
			(layer "F.SilkS")
			(hide yes)
			(effects
				(font
					(size 1.27 1.27)
				)
			)
		)
		(property "Value" ""
			(at 0 0 90)
			(layer "F.Fab")
			(effects
				(font
					(size 1.27 1.27)
				)
			)
		)
		(duplicate_pad_numbers_are_jumpers no)
		(fp_line
			(start 0.7874 -0.4064)
			(end 0.7874 0.4064)
			(stroke
				(width 0.1524)
				(type default)
			)
			(layer "F.SilkS")
		)
		(fp_line
			(start -0.7874 -0.4064)
			(end 0.7874 -0.4064)
			(stroke
				(width 0.1524)
				(type default)
			)
			(layer "F.SilkS")
		)
		(fp_line
			(start 0.7874 0.4064)
			(end -0.7874 0.4064)
			(stroke
				(width 0.1524)
				(type default)
			)
			(layer "F.SilkS")
		)
		(fp_line
			(start -0.7874 0.4064)
			(end -0.7874 -0.4064)
			(stroke
				(width 0.1524)
				(type default)
			)
			(layer "F.SilkS")
		)
		(fp_line
			(start -0.12065 -0.305054)
			(end -0.12065 -0.2794)
			(stroke
				(width 0.1)
				(type default)
			)
			(layer "F.Fab")
		)
		(fp_line
			(start -0.67945 -0.305054)
			(end -0.12065 -0.305054)
			(stroke
				(width 0.1)
				(type default)
			)
			(layer "F.Fab")
		)
		(fp_line
			(start 0.67945 -0.3048)
			(end 0.67945 0.3048)
			(stroke
				(width 0.1)
				(type default)
			)
			(layer "F.Fab")
		)
		(fp_line
			(start 0.12065 -0.3048)
			(end 0.67945 -0.3048)
			(stroke
				(width 0.1)
				(type default)
			)
			(layer "F.Fab")
		)
		(fp_line
			(start 0.12065 -0.2794)
			(end 0.12065 -0.3048)
			(stroke
				(width 0.1)
				(type default)
			)
			(layer "F.Fab")
		)
		(fp_line
			(start -0.12065 -0.2794)
			(end 0.12065 -0.2794)
			(stroke
				(width 0.1)
				(type default)
			)
			(layer "F.Fab")
		)
		(fp_line
			(start 0.120396 0.2794)
			(end -0.12065 0.2794)
			(stroke
				(width 0.1)
				(type default)
			)
			(layer "F.Fab")
		)
		(fp_line
			(start -0.12065 0.2794)
			(end -0.12065 0.3048)
			(stroke
				(width 0.1)
				(type default)
			)
			(layer "F.Fab")
		)
		(fp_line
			(start 0.67945 0.3048)
			(end 0.120396 0.3048)
			(stroke
				(width 0.1)
				(type default)
			)
			(layer "F.Fab")
		)
		(fp_line
			(start 0.120396 0.3048)
			(end 0.120396 0.2794)
			(stroke
				(width 0.1)
				(type default)
			)
			(layer "F.Fab")
		)
		(fp_line
			(start -0.12065 0.3048)
			(end -0.67945 0.3048)
			(stroke
				(width 0.1)
				(type default)
			)
			(layer "F.Fab")
		)
		(fp_line
			(start -0.67945 0.3048)
			(end -0.67945 -0.305054)
			(stroke
				(width 0.1)
				(type default)
			)
			(layer "F.Fab")
		)
		(pad "1" smd circle
			(at -0.40005 0 90)
			(size 0 0)
			(layers "F.Cu" "F.Mask" "F.Paste")
			(net "P3V3_AUX")
		)
		(pad "2" smd circle
			(at 0.40005 0 90)
			(size 0 0)
			(layers "F.Cu" "F.Mask" "F.Paste")
			(net "P12V_SCM_ADC_ALERT_R")
		)
	)
	(footprint ""
		(layer "F.Cu")
		(at 366.48263 -247.715024 90)
		(property "Reference" "C993"
			(at 0 0 90)
			(layer "F.SilkS")
			(hide yes)
			(effects
				(font
					(size 1.27 1.27)
				)
			)
		)
		(property "Value" ""
			(at 0 0 90)
			(layer "F.Fab")
			(effects
				(font
					(size 1.27 1.27)
				)
			)
		)
		(duplicate_pad_numbers_are_jumpers no)
		(fp_line
			(start 0.7874 -0.4064)
			(end 0.7874 0.4064)
			(stroke
				(width 0.1524)
				(type default)
			)
			(layer "F.SilkS")
		)
		(fp_line
			(start -0.7874 -0.4064)
			(end 0.7874 -0.4064)
			(stroke
				(width 0.1524)
				(type default)
			)
			(layer "F.SilkS")
		)
		(fp_line
			(start 0.7874 0.4064)
			(end -0.7874 0.4064)
			(stroke
				(width 0.1524)
				(type default)
			)
			(layer "F.SilkS")
		)
		(fp_line
			(start -0.7874 0.4064)
			(end -0.7874 -0.4064)
			(stroke
				(width 0.1524)
				(type default)
			)
			(layer "F.SilkS")
		)
		(fp_line
			(start -0.12065 -0.305054)
			(end -0.12065 -0.2794)
			(stroke
				(width 0.1)
				(type default)
			)
			(layer "F.Fab")
		)
		(fp_line
			(start -0.67945 -0.305054)
			(end -0.12065 -0.305054)
			(stroke
				(width 0.1)
				(type default)
			)
			(layer "F.Fab")
		)
		(fp_line
			(start 0.67945 -0.3048)
			(end 0.67945 0.3048)
			(stroke
				(width 0.1)
				(type default)
			)
			(layer "F.Fab")
		)
		(fp_line
			(start 0.12065 -0.3048)
			(end 0.67945 -0.3048)
			(stroke
				(width 0.1)
				(type default)
			)
			(layer "F.Fab")
		)
		(fp_line
			(start 0.12065 -0.2794)
			(end 0.12065 -0.3048)
			(stroke
				(width 0.1)
				(type default)
			)
			(layer "F.Fab")
		)
		(fp_line
			(start -0.12065 -0.2794)
			(end 0.12065 -0.2794)
			(stroke
				(width 0.1)
				(type default)
			)
			(layer "F.Fab")
		)
		(fp_line
			(start 0.120396 0.2794)
			(end -0.12065 0.2794)
			(stroke
				(width 0.1)
				(type default)
			)
			(layer "F.Fab")
		)
		(fp_line
			(start -0.12065 0.2794)
			(end -0.12065 0.3048)
			(stroke
				(width 0.1)
				(type default)
			)
			(layer "F.Fab")
		)
		(fp_line
			(start 0.67945 0.3048)
			(end 0.120396 0.3048)
			(stroke
				(width 0.1)
				(type default)
			)
			(layer "F.Fab")
		)
		(fp_line
			(start 0.120396 0.3048)
			(end 0.120396 0.2794)
			(stroke
				(width 0.1)
				(type default)
			)
			(layer "F.Fab")
		)
		(fp_line
			(start -0.12065 0.3048)
			(end -0.67945 0.3048)
			(stroke
				(width 0.1)
				(type default)
			)
			(layer "F.Fab")
		)
		(fp_line
			(start -0.67945 0.3048)
			(end -0.67945 -0.305054)
			(stroke
				(width 0.1)
				(type default)
			)
			(layer "F.Fab")
		)
		(pad "1" smd circle
			(at -0.40005 0 90)
			(size 0 0)
			(layers "F.Cu" "F.Mask" "F.Paste")
			(net "PVCCIN_CPU0")
		)
		(pad "2" smd circle
			(at 0.40005 0 90)
			(size 0 0)
			(layers "F.Cu" "F.Mask" "F.Paste")
			(net "GND")
		)
	)
)
